(kicad_pcb
	(version 20260206)
	(generator "pcbnew")
	(generator_version "10.0")
	(general
		(thickness 1.6)
		(legacy_teardrops no)
	)
	(paper "A4")
	(title_block
		(title "12092022_DA0F0TFB6D0_F0T_FAN_BOARD_MP5048_D_brd_v02_OCP.brd")
		(comment 1 "Grand Teton / footprints 487-491 of 924")
	)
	(layers
		(0 "F.Cu" signal "TOP")
		(4 "In1.Cu" signal "GND")
		(6 "In2.Cu" signal "IN1")
		(8 "In3.Cu" signal "IN2")
		(10 "In4.Cu" signal "GND1")
		(2 "B.Cu" signal "BOTTOM")
		(9 "F.Adhes" user "F.Adhesive")
		(11 "B.Adhes" user "B.Adhesive")
		(13 "F.Paste" user "Package Geometry/Pastemask Top")
		(15 "B.Paste" user "Package Geometry/Pastemask Bottom")
		(5 "F.SilkS" user "Ref Des/Silkscreen Top")
		(7 "B.SilkS" user "Ref Des/Silkscreen Bottom")
		(1 "F.Mask" user "Board Geometry/Soldermask Top")
		(3 "B.Mask" user "Board Geometry/Soldermask Bottom")
		(17 "Dwgs.User" user "User.Drawings")
		(19 "Cmts.User" user "User.Comments")
		(21 "Eco1.User" user "User.Eco1")
		(23 "Eco2.User" user "User.Eco2")
		(25 "Edge.Cuts" user "Board Geometry/Outline")
		(27 "Margin" user)
		(31 "F.CrtYd" user "Package Geometry/Place Bound Top")
		(29 "B.CrtYd" user "Package Geometry/Place Bound Bottom")
		(35 "F.Fab" user "Ref Des/Assembly Top")
		(33 "B.Fab" user "Ref Des/Assembly Bottom")
	)
	(footprint ""
		(layer "F.Cu")
		(at 14.0589 -128.524 180)
		(property "Reference" "R5590"
			(at 0 0 180)
			(layer "F.SilkS")
			(hide yes)
			(effects
				(font
					(size 1.27 1.27)
				)
			)
		)
		(property "Value" ""
			(at 0 0 180)
			(layer "F.Fab")
			(effects
				(font
					(size 1.27 1.27)
				)
			)
		)
		(duplicate_pad_numbers_are_jumpers no)
		(fp_line
			(start 0.7874 0.4064)
			(end -0.7874 0.4064)
			(stroke
				(width 0.1524)
				(type default)
			)
			(layer "F.SilkS")
		)
		(fp_line
			(start 0.7874 -0.4064)
			(end 0.7874 0.4064)
			(stroke
				(width 0.1524)
				(type default)
			)
			(layer "F.SilkS")
		)
		(fp_line
			(start -0.7874 0.4064)
			(end -0.7874 -0.4064)
			(stroke
				(width 0.1524)
				(type default)
			)
			(layer "F.SilkS")
		)
		(fp_line
			(start -0.7874 -0.4064)
			(end 0.7874 -0.4064)
			(stroke
				(width 0.1524)
				(type default)
			)
			(layer "F.SilkS")
		)
		(fp_line
			(start 0.67945 0.3048)
			(end 0.120396 0.3048)
			(stroke
				(width 0.1)
				(type default)
			)
			(layer "F.Fab")
		)
		(fp_line
			(start 0.67945 -0.3048)
			(end 0.67945 0.3048)
			(stroke
				(width 0.1)
				(type default)
			)
			(layer "F.Fab")
		)
		(fp_line
			(start 0.12065 -0.2794)
			(end 0.12065 -0.3048)
			(stroke
				(width 0.1)
				(type default)
			)
			(layer "F.Fab")
		)
		(fp_line
			(start 0.12065 -0.3048)
			(end 0.67945 -0.3048)
			(stroke
				(width 0.1)
				(type default)
			)
			(layer "F.Fab")
		)
		(fp_line
			(start 0.120396 0.3048)
			(end 0.120396 0.2794)
			(stroke
				(width 0.1)
				(type default)
			)
			(layer "F.Fab")
		)
		(fp_line
			(start 0.120396 0.2794)
			(end -0.12065 0.2794)
			(stroke
				(width 0.1)
				(type default)
			)
			(layer "F.Fab")
		)
		(fp_line
			(start -0.12065 0.3048)
			(end -0.67945 0.3048)
			(stroke
				(width 0.1)
				(type default)
			)
			(layer "F.Fab")
		)
		(fp_line
			(start -0.12065 0.2794)
			(end -0.12065 0.3048)
			(stroke
				(width 0.1)
				(type default)
			)
			(layer "F.Fab")
		)
		(fp_line
			(start -0.12065 -0.2794)
			(end 0.12065 -0.2794)
			(stroke
				(width 0.1)
				(type default)
			)
			(layer "F.Fab")
		)
		(fp_line
			(start -0.12065 -0.305054)
			(end -0.12065 -0.2794)
			(stroke
				(width 0.1)
				(type default)
			)
			(layer "F.Fab")
		)
		(fp_line
			(start -0.67945 0.3048)
			(end -0.67945 -0.305054)
			(stroke
				(width 0.1)
				(type default)
			)
			(layer "F.Fab")
		)
		(fp_line
			(start -0.67945 -0.305054)
			(end -0.12065 -0.305054)
			(stroke
				(width 0.1)
				(type default)
			)
			(layer "F.Fab")
		)
		(pad "1" smd rect
			(at -0.40005 0)
			(size 0.4572 0.508)
			(layers "F.Cu" "F.Mask" "F.Paste")
			(net "FAN_5_TACH_OL")
		)
		(pad "2" smd rect
			(at 0.40005 0)
			(size 0.4572 0.508)
			(layers "F.Cu" "F.Mask" "F.Paste")
			(net "FAN_5_TACH_OL_R2")
		)
	)
	(footprint ""
		(layer "F.Cu")
		(at 19.558 -110.236 -90)
		(property "Reference" "R5362"
			(at 0 0 270)
			(layer "F.SilkS")
			(hide yes)
			(effects
				(font
					(size 1.27 1.27)
				)
			)
		)
		(property "Value" ""
			(at 0 0 270)
			(layer "F.Fab")
			(effects
				(font
					(size 1.27 1.27)
				)
			)
		)
		(duplicate_pad_numbers_are_jumpers no)
		(fp_line
			(start -0.7874 0.4064)
			(end -0.7874 -0.4064)
			(stroke
				(width 0.1524)
				(type default)
			)
			(layer "F.SilkS")
		)
		(fp_line
			(start 0.7874 0.4064)
			(end -0.7874 0.4064)
			(stroke
				(width 0.1524)
				(type default)
			)
			(layer "F.SilkS")
		)
		(fp_line
			(start -0.7874 -0.4064)
			(end 0.7874 -0.4064)
			(stroke
				(width 0.1524)
				(type default)
			)
			(layer "F.SilkS")
		)
		(fp_line
			(start 0.7874 -0.4064)
			(end 0.7874 0.4064)
			(stroke
				(width 0.1524)
				(type default)
			)
			(layer "F.SilkS")
		)
		(fp_line
			(start -0.67945 0.3048)
			(end -0.67945 -0.305054)
			(stroke
				(width 0.1)
				(type default)
			)
			(layer "F.Fab")
		)
		(fp_line
			(start -0.12065 0.3048)
			(end -0.67945 0.3048)
			(stroke
				(width 0.1)
				(type default)
			)
			(layer "F.Fab")
		)
		(fp_line
			(start 0.120396 0.3048)
			(end 0.120396 0.2794)
			(stroke
				(width 0.1)
				(type default)
			)
			(layer "F.Fab")
		)
		(fp_line
			(start 0.67945 0.3048)
			(end 0.120396 0.3048)
			(stroke
				(width 0.1)
				(type default)
			)
			(layer "F.Fab")
		)
		(fp_line
			(start -0.12065 0.2794)
			(end -0.12065 0.3048)
			(stroke
				(width 0.1)
				(type default)
			)
			(layer "F.Fab")
		)
		(fp_line
			(start 0.120396 0.2794)
			(end -0.12065 0.2794)
			(stroke
				(width 0.1)
				(type default)
			)
			(layer "F.Fab")
		)
		(fp_line
			(start -0.12065 -0.2794)
			(end 0.12065 -0.2794)
			(stroke
				(width 0.1)
				(type default)
			)
			(layer "F.Fab")
		)
		(fp_line
			(start 0.12065 -0.2794)
			(end 0.12065 -0.3048)
			(stroke
				(width 0.1)
				(type default)
			)
			(layer "F.Fab")
		)
		(fp_line
			(start 0.12065 -0.3048)
			(end 0.67945 -0.3048)
			(stroke
				(width 0.1)
				(type default)
			)
			(layer "F.Fab")
		)
		(fp_line
			(start 0.67945 -0.3048)
			(end 0.67945 0.3048)
			(stroke
				(width 0.1)
				(type default)
			)
			(layer "F.Fab")
		)
		(fp_line
			(start -0.67945 -0.305054)
			(end -0.12065 -0.305054)
			(stroke
				(width 0.1)
				(type default)
			)
			(layer "F.Fab")
		)
		(fp_line
			(start -0.12065 -0.305054)
			(end -0.12065 -0.2794)
			(stroke
				(width 0.1)
				(type default)
			)
			(layer "F.Fab")
		)
		(pad "1" smd circle
			(at -0.40005 0 270)
			(size 0 0)
			(layers "F.Cu" "F.Mask" "F.Paste")
			(net "P3V3_AUX")
		)
		(pad "2" smd circle
			(at 0.40005 0 270)
			(size 0 0)
			(layers "F.Cu" "F.Mask" "F.Paste")
			(net "FAN_5_FAIL_R_LED")
		)
	)
	(footprint ""
		(layer "F.Cu")
		(at 48.26 -217.424)
		(property "Reference" "Q10"
			(at -0.75692 2.67335 0)
			(unlocked yes)
			(layer "F.SilkS")
			(effects
				(font
					(size 0.7874 0.5842)
					(thickness 0.1524)
				)
				(justify left)
			)
		)
		(property "Value" ""
			(at 0 0 0)
			(layer "F.Fab")
			(effects
				(font
					(size 1.27 1.27)
				)
			)
		)
		(duplicate_pad_numbers_are_jumpers no)
		(fp_line
			(start -1.905 -1.651)
			(end 1.905 -1.651)
			(stroke
				(width 0.1524)
				(type default)
			)
			(layer "F.SilkS")
		)
		(fp_line
			(start -1.905 1.651)
			(end -1.905 -1.651)
			(stroke
				(width 0.1524)
				(type default)
			)
			(layer "F.SilkS")
		)
		(fp_line
			(start 1.905 -1.651)
			(end 1.905 1.651)
			(stroke
				(width 0.1524)
				(type default)
			)
			(layer "F.SilkS")
		)
		(fp_line
			(start 1.905 1.651)
			(end -1.905 1.651)
			(stroke
				(width 0.1524)
				(type default)
			)
			(layer "F.SilkS")
		)
		(fp_line
			(start -1.249934 -1.169924)
			(end -0.6985 -1.169924)
			(stroke
				(width 0.1)
				(type default)
			)
			(layer "F.Fab")
		)
		(fp_line
			(start -1.249934 -0.729996)
			(end -1.249934 -1.169924)
			(stroke
				(width 0.1)
				(type default)
			)
			(layer "F.Fab")
		)
		(fp_line
			(start -1.249934 0.729996)
			(end -0.6985 0.729996)
			(stroke
				(width 0.1)
				(type default)
			)
			(layer "F.Fab")
		)
		(fp_line
			(start -1.249934 1.169924)
			(end -1.249934 0.729996)
			(stroke
				(width 0.1)
				(type default)
			)
			(layer "F.Fab")
		)
		(fp_line
			(start -0.6985 -1.524)
			(end 0.6985 -1.524)
			(stroke
				(width 0.1)
				(type default)
			)
			(layer "F.Fab")
		)
		(fp_line
			(start -0.6985 -1.169924)
			(end -0.6985 -1.524)
			(stroke
				(width 0.1)
				(type default)
			)
			(layer "F.Fab")
		)
		(fp_line
			(start -0.6985 -0.729996)
			(end -1.249934 -0.729996)
			(stroke
				(width 0.1)
				(type default)
			)
			(layer "F.Fab")
		)
		(fp_line
			(start -0.6985 0.729996)
			(end -0.6985 -0.729996)
			(stroke
				(width 0.1)
				(type default)
			)
			(layer "F.Fab")
		)
		(fp_line
			(start -0.6985 1.169924)
			(end -1.249934 1.169924)
			(stroke
				(width 0.1)
				(type default)
			)
			(layer "F.Fab")
		)
		(fp_line
			(start -0.6985 1.524)
			(end -0.6985 1.169924)
			(stroke
				(width 0.1)
				(type default)
			)
			(layer "F.Fab")
		)
		(fp_line
			(start 0.6985 -1.524)
			(end 0.6985 -0.219964)
			(stroke
				(width 0.1)
				(type default)
			)
			(layer "F.Fab")
		)
		(fp_line
			(start 0.6985 -0.219964)
			(end 1.249934 -0.219964)
			(stroke
				(width 0.1)
				(type default)
			)
			(layer "F.Fab")
		)
		(fp_line
			(start 0.6985 0.219964)
			(end 0.6985 1.524)
			(stroke
				(width 0.1)
				(type default)
			)
			(layer "F.Fab")
		)
		(fp_line
			(start 0.6985 1.524)
			(end -0.6985 1.524)
			(stroke
				(width 0.1)
				(type default)
			)
			(layer "F.Fab")
		)
		(fp_line
			(start 1.249934 -0.219964)
			(end 1.249934 0.219964)
			(stroke
				(width 0.1)
				(type default)
			)
			(layer "F.Fab")
		)
		(fp_line
			(start 1.249934 0.219964)
			(end 0.6985 0.219964)
			(stroke
				(width 0.1)
				(type default)
			)
			(layer "F.Fab")
		)
		(fp_rect
			(start -0.6985 1.524)
			(end 0.6985 -1.524)
			(stroke
				(width 0)
				(type default)
			)
			(fill no)
			(layer "F.Fab")
		)
		(pad "D" smd rect
			(at 1.1176 0 270)
			(size 1.016 1.27)
			(layers "F.Cu" "F.Mask" "F.Paste")
			(net "P12V_LED_FAN1")
		)
		(pad "G" smd rect
			(at -1.1176 -1.016 270)
			(size 1.016 1.27)
			(layers "F.Cu" "F.Mask" "F.Paste")
			(net "U406_D1")
		)
		(pad "S" smd rect
			(at -1.1176 1.016 270)
			(size 1.016 1.27)
			(layers "F.Cu" "F.Mask" "F.Paste")
			(net "P12V_LED")
		)
	)
	(footprint ""
		(layer "F.Cu")
		(at 33.401 -141.351 -90)
		(property "Reference" "R5283"
			(at 0 0 270)
			(layer "F.SilkS")
			(hide yes)
			(effects
				(font
					(size 1.27 1.27)
				)
			)
		)
		(property "Value" ""
			(at 0 0 270)
			(layer "F.Fab")
			(effects
				(font
					(size 1.27 1.27)
				)
			)
		)
		(duplicate_pad_numbers_are_jumpers no)
		(fp_line
			(start -0.7874 0.4064)
			(end -0.7874 -0.4064)
			(stroke
				(width 0.1524)
				(type default)
			)
			(layer "F.SilkS")
		)
		(fp_line
			(start 0.7874 0.4064)
			(end -0.7874 0.4064)
			(stroke
				(width 0.1524)
				(type default)
			)
			(layer "F.SilkS")
		)
		(fp_line
			(start -0.7874 -0.4064)
			(end 0.7874 -0.4064)
			(stroke
				(width 0.1524)
				(type default)
			)
			(layer "F.SilkS")
		)
		(fp_line
			(start 0.7874 -0.4064)
			(end 0.7874 0.4064)
			(stroke
				(width 0.1524)
				(type default)
			)
			(layer "F.SilkS")
		)
		(fp_line
			(start -0.67945 0.3048)
			(end -0.67945 -0.305054)
			(stroke
				(width 0.1)
				(type default)
			)
			(layer "F.Fab")
		)
		(fp_line
			(start -0.12065 0.3048)
			(end -0.67945 0.3048)
			(stroke
				(width 0.1)
				(type default)
			)
			(layer "F.Fab")
		)
		(fp_line
			(start 0.120396 0.3048)
			(end 0.120396 0.2794)
			(stroke
				(width 0.1)
				(type default)
			)
			(layer "F.Fab")
		)
		(fp_line
			(start 0.67945 0.3048)
			(end 0.120396 0.3048)
			(stroke
				(width 0.1)
				(type default)
			)
			(layer "F.Fab")
		)
		(fp_line
			(start -0.12065 0.2794)
			(end -0.12065 0.3048)
			(stroke
				(width 0.1)
				(type default)
			)
			(layer "F.Fab")
		)
		(fp_line
			(start 0.120396 0.2794)
			(end -0.12065 0.2794)
			(stroke
				(width 0.1)
				(type default)
			)
			(layer "F.Fab")
		)
		(fp_line
			(start -0.12065 -0.2794)
			(end 0.12065 -0.2794)
			(stroke
				(width 0.1)
				(type default)
			)
			(layer "F.Fab")
		)
		(fp_line
			(start 0.12065 -0.2794)
			(end 0.12065 -0.3048)
			(stroke
				(width 0.1)
				(type default)
			)
			(layer "F.Fab")
		)
		(fp_line
			(start 0.12065 -0.3048)
			(end 0.67945 -0.3048)
			(stroke
				(width 0.1)
				(type default)
			)
			(layer "F.Fab")
		)
		(fp_line
			(start 0.67945 -0.3048)
			(end 0.67945 0.3048)
			(stroke
				(width 0.1)
				(type default)
			)
			(layer "F.Fab")
		)
		(fp_line
			(start -0.67945 -0.305054)
			(end -0.12065 -0.305054)
			(stroke
				(width 0.1)
				(type default)
			)
			(layer "F.Fab")
		)
		(fp_line
			(start -0.12065 -0.305054)
			(end -0.12065 -0.2794)
			(stroke
				(width 0.1)
				(type default)
			)
			(layer "F.Fab")
		)
		(pad "1" smd circle
			(at -0.40005 0 270)
			(size 0 0)
			(layers "F.Cu" "F.Mask" "F.Paste")
			(net "SMB_FAN3_R_SDA")
		)
		(pad "2" smd circle
			(at 0.40005 0 270)
			(size 0 0)
			(layers "F.Cu" "F.Mask" "F.Paste")
			(net "P3V3_AUX")
		)
	)
	(footprint ""
		(layer "F.Cu")
		(at 36.449 -14.351 -90)
		(property "Reference" "C2055"
			(at 0 0 270)
			(layer "F.SilkS")
			(hide yes)
			(effects
				(font
					(size 1.27 1.27)
				)
			)
		)
		(property "Value" ""
			(at 0 0 270)
			(layer "F.Fab")
			(effects
				(font
					(size 1.27 1.27)
				)
			)
		)
		(duplicate_pad_numbers_are_jumpers no)
		(fp_line
			(start -0.7874 0.4064)
			(end -0.7874 -0.4064)
			(stroke
				(width 0.1524)
				(type default)
			)
			(layer "F.SilkS")
		)
		(fp_line
			(start 0.7874 0.4064)
			(end -0.7874 0.4064)
			(stroke
				(width 0.1524)
				(type default)
			)
			(layer "F.SilkS")
		)
		(fp_line
			(start -0.7874 -0.4064)
			(end 0.7874 -0.4064)
			(stroke
				(width 0.1524)
				(type default)
			)
			(layer "F.SilkS")
		)
		(fp_line
			(start 0.7874 -0.4064)
			(end 0.7874 0.4064)
			(stroke
				(width 0.1524)
				(type default)
			)
			(layer "F.SilkS")
		)
		(fp_line
			(start -0.67945 0.3048)
			(end -0.67945 -0.305054)
			(stroke
				(width 0.1)
				(type default)
			)
			(layer "F.Fab")
		)
		(fp_line
			(start -0.12065 0.3048)
			(end -0.67945 0.3048)
			(stroke
				(width 0.1)
				(type default)
			)
			(layer "F.Fab")
		)
		(fp_line
			(start 0.120396 0.3048)
			(end 0.120396 0.2794)
			(stroke
				(width 0.1)
				(type default)
			)
			(layer "F.Fab")
		)
		(fp_line
			(start 0.67945 0.3048)
			(end 0.120396 0.3048)
			(stroke
				(width 0.1)
				(type default)
			)
			(layer "F.Fab")
		)
		(fp_line
			(start -0.12065 0.2794)
			(end -0.12065 0.3048)
			(stroke
				(width 0.1)
				(type default)
			)
			(layer "F.Fab")
		)
		(fp_line
			(start 0.120396 0.2794)
			(end -0.12065 0.2794)
			(stroke
				(width 0.1)
				(type default)
			)
			(layer "F.Fab")
		)
		(fp_line
			(start -0.12065 -0.2794)
			(end 0.12065 -0.2794)
			(stroke
				(width 0.1)
				(type default)
			)
			(layer "F.Fab")
		)
		(fp_line
			(start 0.12065 -0.2794)
			(end 0.12065 -0.3048)
			(stroke
				(width 0.1)
				(type default)
			)
			(layer "F.Fab")
		)
		(fp_line
			(start 0.12065 -0.3048)
			(end 0.67945 -0.3048)
			(stroke
				(width 0.1)
				(type default)
			)
			(layer "F.Fab")
		)
		(fp_line
			(start 0.67945 -0.3048)
			(end 0.67945 0.3048)
			(stroke
				(width 0.1)
				(type default)
			)
			(layer "F.Fab")
		)
		(fp_line
			(start -0.67945 -0.305054)
			(end -0.12065 -0.305054)
			(stroke
				(width 0.1)
				(type default)
			)
			(layer "F.Fab")
		)
		(fp_line
			(start -0.12065 -0.305054)
			(end -0.12065 -0.2794)
			(stroke
				(width 0.1)
				(type default)
			)
			(layer "F.Fab")
		)
		(pad "1" smd circle
			(at -0.40005 0 270)
			(size 0 0)
			(layers "F.Cu" "F.Mask" "F.Paste")
			(net "FAN_3_TACH_OL_R")
		)
		(pad "2" smd circle
			(at 0.40005 0 270)
			(size 0 0)
			(layers "F.Cu" "F.Mask" "F.Paste")
			(net "GND")
		)
	)
)
